#ISCELL
  mstr_misc dns *
  *
#ISCELL
  pure_quanta quanta_title_block_c *
  *
#ISCELL
  standard offpage *
  page183_i1
#ISCELL
  pure_quanta_power universal_gnd *
  page183_i10
#CELL
  pure_quanta q_res *
  page183_i11
#ISCELL
  standard offpage *
  page183_i12
#CELL
  pure_quanta isl99390frztr5935 *
  page183_i13
#CELL
  pure_quanta q_res *
  page183_i14
#ISCELL
  pure_quanta_power vcc_core *
  page183_i15
#ISCELL
  pure_quanta_power universal_gnd *
  page183_i16
#CELL
  pure_quanta q_cap *
  page183_i17
#ISCELL
  pure_quanta_power universal_gnd *
  page183_i18
#ISCELL
  pure_quanta_power universal_gnd *
  page183_i19
#ISCELL
  standard offpage *
  page183_i2
#ISCELL
  standard offpage *
  page183_i20
#ISCELL
  standard offpage *
  page183_i21
#ISCELL
  pure_quanta_power universal_gnd *
  page183_i22
#ISCELL
  pure_quanta_power universal_gnd *
  page183_i23
#CELL
  pure_quanta q_res *
  page183_i24
#CELL
  pure_quanta q_res *
  page183_i25
#CELL
  pure_quanta q_cap *
  page183_i26
#CELL
  pure_quanta q_cap *
  page183_i27
#ISCELL
  pure_quanta_power universal_gnd *
  page183_i28
#CELL
  pure_quanta q_cap *
  page183_i29
#ISCELL
  pure_quanta_power vcc_core *
  page183_i3
#CELL
  pure_quanta q_cap *
  page183_i30
#CELL
  pure_quanta q_cap *
  page183_i31
#ISCELL
  pure_quanta_power universal_gnd *
  page183_i32
#CELL
  pure_quanta q_res *
  page183_i33
#CELL
  pure_quanta q_cap *
  page183_i34
#ISCELL
  pure_quanta_power universal_gnd *
  page183_i35
#CELL
  pure_quanta q_cap *
  page183_i36
#CELL
  pure_quanta q_res *
  page183_i37
#ISCELL
  standard offpage *
  page183_i38
#ISCELL
  pure_quanta_power universal_gnd *
  page183_i39
#ISCELL
  pure_quanta_power universal_gnd *
  page183_i4
#CELL
  pure_quanta q_res *
  page183_i40
#ISCELL
  pure_quanta_power vcc_core *
  page183_i41
#CELL
  pure_quanta q_cap *
  page183_i42
#ISCELL
  pure_quanta_power vcc_core *
  page183_i43
#CELL
  pure_quanta q_cap *
  page183_i44
#CELL
  pure_quanta q_cap *
  page183_i45
#CELL
  pure_quanta q_res *
  page183_i46
#CELL
  pure_quanta q_cap *
  page183_i47
#CELL
  pure_quanta q_cap *
  page183_i48
#CELL
  pure_quanta q_cap *
  page183_i49
#ISCELL
  standard offpage *
  page183_i5
#CELL
  pure_quanta q_cap *
  page183_i50
#CELL
  pure_quanta q_cap *
  page183_i51
#CELL
  pure_quanta q_inductor *
  page183_i52
#ISCELL
  pure_quanta_power universal_gnd *
  page183_i53
#CELL
  pure_quanta q_cap *
  page183_i54
#ISCELL
  pure_quanta_power vcc_core *
  page183_i55
#CELL
  pure_quanta q_res *
  page183_i56
#ISCELL
  pure_quanta_power universal_gnd *
  page183_i57
#CELL
  pure_quanta q_capp *
  page183_i58
#CELL
  pure_quanta q_capp *
  page183_i59
#ISCELL
  standard offpage *
  page183_i6
#ISCELL
  pure_quanta_power vcc_core *
  page183_i60
#ISCELL
  pure_quanta_power universal_gnd *
  page183_i61
#CELL
  pure_quanta q_cap *
  page183_i62
#ISCELL
  pure_quanta_power vcc_core *
  page183_i63
#ISCELL
  pure_quanta_power universal_gnd *
  page183_i64
#CELL
  pure_quanta q_capp *
  page183_i65
#CELL
  pure_quanta q_capp *
  page183_i66
#CELL
  pure_quanta q_capp *
  page183_i67
#ISCELL
  pure_quanta_power vcc_core *
  page183_i68
#ISCELL
  pure_quanta_power universal_gnd *
  page183_i69
#CELL
  pure_quanta q_cap *
  page183_i7
#CELL
  pure_quanta q_capp *
  page183_i70
#CELL
  pure_quanta q_cap *
  page183_i71
#ISCELL
  pure_quanta_power universal_gnd *
  page183_i72
#CELL
  pure_quanta q_inductor *
  page183_i73
#ISCELL
  pure_quanta_power vcc_core *
  page183_i74
#CELL
  pure_quanta q_capp *
  page183_i75
#CELL
  pure_quanta q_cap *
  page183_i76
#ISCELL
  pure_quanta_power universal_gnd *
  page183_i77
#CELL
  pure_quanta q_inductor *
  page183_i78
#CELL
  pure_quanta q_cap *
  page183_i79
#ISCELL
  pure_quanta_power universal_gnd *
  page183_i8
#ISCELL
  pure_quanta_power vcc_core *
  page183_i80
#CELL
  pure_quanta q_cap *
  page183_i81
#CELL
  pure_quanta q_cap *
  page183_i82
#CELL
  pure_quanta q_res *
  page183_i83
#ISCELL
  pure_quanta_power vcc_core *
  page183_i84
#CELL
  pure_quanta q_res *
  page183_i85
#CELL
  pure_quanta q_res *
  page183_i86
#CELL
  pure_quanta q_cap *
  page183_i87
#CELL
  pure_quanta q_cap *
  page183_i88
#CELL
  pure_quanta q_capp *
  page183_i89
#CELL
  pure_quanta q_cap *
  page183_i9
#CELL
  pure_quanta q_cap *
  page183_i90
#CELL
  pure_quanta q_res *
  page183_i91
#CELL
  pure_quanta isl99390frztr5935 *
  page183_i92
#CELL
  pure_quanta q_cap *
  page183_i93
#CELL
  pure_quanta q_cap *
  page183_i94
#CELL
  pure_quanta q_cap *
  page183_i95
